# BASEBOARD_FAB2 (Tioga Pass) — schematic netlist excerpt (pin names and nets, part order shuffled) for the footprints in the layout excerpt that follows; sources: Cadence DE-HDL packaged netlist, KiCad conversion of Wiwynn_Tioga_Pass_MB.brd

C4D26  CAP_A  0.1UF 16V 10% X7R  pkg 0402V  page 201 : A = VR_PVCCIN_CPU0_VD12 ; B = GND
R25W49  120R2F-GP  1%  pkg RCL_GP  page 151 : \1\ = BMC_M_A11 ; \2\ = P1V2_AUX_BMC
R2M3  RES  33.2 1% CHIP  pkg 0402  page 119 : A = FM_PCH_PLD_DATA_R ; B = FM_PCH_PLD_DATA

(kicad_pcb
	(version 20260206)
	(generator "pcbnew")
	(generator_version "10.0")
	(general
		(thickness 1.6)
		(legacy_teardrops no)
	)
	(paper "A4")
	(title_block
		(title "Wiwynn_Tioga_Pass_MB.brd")
		(comment 1 "Tioga Pass / footprints 47-49 of 4770")
	)
	(layers
		(0 "F.Cu" signal "TOP")
		(4 "In1.Cu" signal "L2GND")
		(6 "In2.Cu" signal "L3")
		(8 "In3.Cu" signal "L4GND")
		(10 "In4.Cu" signal "L5")
		(12 "In5.Cu" signal "L6GND")
		(14 "In6.Cu" signal "L7VCC")
		(16 "In7.Cu" signal "L8VCC")
		(18 "In8.Cu" signal "L9GND")
		(20 "In9.Cu" signal "L10")
		(22 "In10.Cu" signal "L11GND")
		(24 "In11.Cu" signal "L12")
		(26 "In12.Cu" signal "L13GND")
		(2 "B.Cu" signal "BOTTOM")
		(9 "F.Adhes" user "F.Adhesive")
		(11 "B.Adhes" user "B.Adhesive")
		(13 "F.Paste" user "Package Geometry/Pastemask Top")
		(15 "B.Paste" user "Package Geometry/Pastemask Bottom")
		(5 "F.SilkS" user "Ref Des/Silkscreen Top")
		(7 "B.SilkS" user "Ref Des/Silkscreen Bottom")
		(1 "F.Mask" user "Board Geometry/Soldermask Top")
		(3 "B.Mask" user "Board Geometry/Soldermask Bottom")
		(17 "Dwgs.User" user "User.Drawings")
		(19 "Cmts.User" user "User.Comments")
		(21 "Eco1.User" user "User.Eco1")
		(23 "Eco2.User" user "User.Eco2")
		(25 "Edge.Cuts" user "Board Geometry/Outline")
		(27 "Margin" user)
		(31 "F.CrtYd" user "Package Geometry/Place Bound Top")
		(29 "B.CrtYd" user "Package Geometry/Place Bound Bottom")
		(35 "F.Fab" user "Ref Des/Assembly Top")
		(33 "B.Fab" user "Ref Des/Assembly Bottom")
	)
	(footprint ""
		(layer "F.Cu")
		(at 415.7345 -110.617 -90)
		(property "Reference" "R2M3"
			(at 0 0 270)
			(layer "F.SilkS")
			(hide yes)
			(effects
				(font
					(size 1.27 1.27)
				)
			)
		)
		(property "Value" ""
			(at 0 0 270)
			(layer "F.Fab")
			(effects
				(font
					(size 1.27 1.27)
				)
			)
		)
		(duplicate_pad_numbers_are_jumpers no)
		(fp_poly
			(pts
				(xy -0.2794 -0.1016) (xy 0.2794 -0.1016) (xy 0.2794 0.9906) (xy -0.2794 0.9906)
			)
			(stroke
				(width 0)
				(type default)
			)
			(fill no)
			(layer "F.CrtYd")
		)
		(fp_line
			(start -0.2794 0.9906)
			(end 0.2794 0.9906)
			(stroke
				(width 0.1)
				(type default)
			)
			(layer "F.Fab")
		)
		(fp_line
			(start 0.2794 0.9906)
			(end 0.2794 -0.1016)
			(stroke
				(width 0.1)
				(type default)
			)
			(layer "F.Fab")
		)
		(fp_line
			(start -0.2794 -0.1016)
			(end -0.2794 0.9906)
			(stroke
				(width 0.1)
				(type default)
			)
			(layer "F.Fab")
		)
		(fp_line
			(start 0.2794 -0.1016)
			(end -0.2794 -0.1016)
			(stroke
				(width 0.1)
				(type default)
			)
			(layer "F.Fab")
		)
		(pad "1" smd rect
			(at 0 0 270)
			(size 0.508 0.508)
			(layers "F.Cu" "F.Mask" "F.Paste")
			(net "FM_PCH_PLD_DATA_R")
		)
		(pad "2" smd rect
			(at 0 0.889 270)
			(size 0.508 0.508)
			(layers "F.Cu" "F.Mask" "F.Paste")
			(net "FM_PCH_PLD_DATA")
		)
		(zone
			(layer "F.Cu")
			(hatch none 0.5)
			(connect_pads
				(clearance 0)
			)
			(min_thickness 0.25)
			(keepout
				(tracks not_allowed)
				(vias allowed)
				(pads allowed)
				(copperpour not_allowed)
				(footprints allowed)
			)
			(placement
				(enabled no)
				(sheetname "")
			)
			(fill
				(thermal_gap 0.5)
				(thermal_bridge_width 0.5)
				(island_removal_mode 0)
			)
			(polygon
				(pts
					(xy 415.0995 -110.871) (xy 415.0995 -110.363) (xy 415.4805 -110.363) (xy 415.4805 -110.871)
				)
			)
		)
		(zone
			(layer "F.Cu")
			(hatch none 0.5)
			(connect_pads
				(clearance 0)
			)
			(min_thickness 0.25)
			(keepout
				(tracks allowed)
				(vias not_allowed)
				(pads allowed)
				(copperpour not_allowed)
				(footprints allowed)
			)
			(placement
				(enabled no)
				(sheetname "")
			)
			(fill
				(thermal_gap 0.5)
				(thermal_bridge_width 0.5)
				(island_removal_mode 0)
			)
			(polygon
				(pts
					(xy 415.4805 -110.871) (xy 415.4805 -110.363) (xy 415.0995 -110.363) (xy 415.0995 -110.871)
				)
			)
		)
	)
	(footprint ""
		(layer "F.Cu")
		(at 451.85838 -38.2905 90)
		(property "Reference" "R25W49"
			(at 0 0 90)
			(layer "F.SilkS")
			(hide yes)
			(effects
				(font
					(size 1.27 1.27)
				)
			)
		)
		(property "Value" "*"
			(at 0.064008 -4.108196 90)
			(unlocked yes)
			(layer "F.Fab")
			(hide yes)
			(effects
				(font
					(size 1.27 1.016)
					(thickness 0.1524)
				)
			)
		)
		(property "Device Type" "120R2F-GP_RCL_GP-120R2F-GP,64.A"
			(at 0.064008 -5.632196 90)
			(unlocked yes)
			(layer "F.Fab")
			(hide yes)
			(effects
				(font
					(size 1.27 1.016)
					(thickness 0.1524)
				)
			)
		)
		(duplicate_pad_numbers_are_jumpers no)
		(fp_line
			(start 0.508 -0.9398)
			(end -0.508 -0.9398)
			(stroke
				(width 0.1524)
				(type default)
			)
			(layer "F.SilkS")
		)
		(fp_line
			(start -0.508 -0.9398)
			(end -0.508 0.9398)
			(stroke
				(width 0.1524)
				(type default)
			)
			(layer "F.SilkS")
		)
		(fp_rect
			(start -0.508 0.9398)
			(end 0.508 -0.9398)
			(stroke
				(width 0)
				(type default)
			)
			(fill no)
			(layer "F.CrtYd")
		)
		(fp_rect
			(start -0.508 0.9398)
			(end 0.508 -0.9398)
			(stroke
				(width 0)
				(type default)
			)
			(fill no)
			(layer "F.Fab")
		)
		(pad "1" smd custom
			(at 0 -0.4445 90)
			(size 0.1397 0.1397)
			(layers "F.Cu" "F.Mask" "F.Paste")
			(net "BMC_M_A11")
			(options
				(clearance outline)
				(anchor circle)
			)
			(primitives
				(gr_poly
					(pts
						(arc
							(start -0.1778 -0.2794)
							(mid -0.249642 -0.249642)
							(end -0.2794 -0.1778)
						)
						(arc
							(start -0.2794 0.1778)
							(mid -0.249642 0.249642)
							(end -0.1778 0.2794)
						)
						(arc
							(start 0.1778 0.2794)
							(mid 0.249642 0.249642)
							(end 0.2794 0.1778)
						)
						(arc
							(start 0.2794 -0.1778)
							(mid 0.249642 -0.249642)
							(end 0.1778 -0.2794)
						)
					)
					(width 0)
					(fill yes)
				)
			)
		)
		(pad "2" smd custom
			(at 0 0.4445 90)
			(size 0.1397 0.1397)
			(layers "F.Cu" "F.Mask" "F.Paste")
			(net "P1V2_AUX_BMC")
			(options
				(clearance outline)
				(anchor circle)
			)
			(primitives
				(gr_poly
					(pts
						(arc
							(start -0.1778 -0.2794)
							(mid -0.249642 -0.249642)
							(end -0.2794 -0.1778)
						)
						(arc
							(start -0.2794 0.1778)
							(mid -0.249642 0.249642)
							(end -0.1778 0.2794)
						)
						(arc
							(start 0.1778 0.2794)
							(mid 0.249642 0.249642)
							(end 0.2794 0.1778)
						)
						(arc
							(start 0.2794 -0.1778)
							(mid 0.249642 -0.249642)
							(end 0.1778 -0.2794)
						)
					)
					(width 0)
					(fill yes)
				)
			)
		)
	)
	(footprint ""
		(layer "F.Cu")
		(at 180.381148 -73.85685 -90)
		(property "Reference" "C4D26"
			(at 0 0 270)
			(layer "F.SilkS")
			(hide yes)
			(effects
				(font
					(size 1.27 1.27)
				)
			)
		)
		(property "Value" ""
			(at 0 0 270)
			(layer "F.Fab")
			(effects
				(font
					(size 1.27 1.27)
				)
			)
		)
		(duplicate_pad_numbers_are_jumpers no)
		(fp_rect
			(start 0.3048 -0.1016)
			(end -0.3048 0.9906)
			(stroke
				(width 0)
				(type default)
			)
			(fill no)
			(layer "F.CrtYd")
		)
		(fp_line
			(start -0.3048 0.9906)
			(end 0.3048 0.9906)
			(stroke
				(width 0.1)
				(type default)
			)
			(layer "F.Fab")
		)
		(fp_line
			(start 0.3048 0.9906)
			(end 0.3048 -0.1016)
			(stroke
				(width 0.1)
				(type default)
			)
			(layer "F.Fab")
		)
		(fp_line
			(start -0.3048 -0.1016)
			(end -0.3048 0.9906)
			(stroke
				(width 0.1)
				(type default)
			)
			(layer "F.Fab")
		)
		(fp_line
			(start 0.3048 -0.1016)
			(end -0.3048 -0.1016)
			(stroke
				(width 0.1)
				(type default)
			)
			(layer "F.Fab")
		)
		(pad "1" smd rect
			(at 0 0 270)
			(size 0.508 0.508)
			(layers "F.Cu" "F.Mask" "F.Paste")
			(net "VR_PVCCIN_CPU0_VD12")
		)
		(pad "2" smd rect
			(at 0 0.889 270)
			(size 0.508 0.508)
			(layers "F.Cu" "F.Mask" "F.Paste")
			(net "GND")
		)
		(zone
			(layer "F.Cu")
			(hatch none 0.5)
			(connect_pads
				(clearance 0)
			)
			(min_thickness 0.25)
			(keepout
				(tracks not_allowed)
				(vias allowed)
				(pads allowed)
				(copperpour not_allowed)
				(footprints allowed)
			)
			(placement
				(enabled no)
				(sheetname "")
			)
			(fill
				(thermal_gap 0.5)
				(thermal_bridge_width 0.5)
				(island_removal_mode 0)
			)
			(polygon
				(pts
					(xy 180.127148 -73.60285) (xy 180.127148 -74.11085) (xy 179.746148 -74.11085) (xy 179.746148 -73.60285)
				)
			)
		)
		(zone
			(layer "F.Cu")
			(hatch none 0.5)
			(connect_pads
				(clearance 0)
			)
			(min_thickness 0.25)
			(keepout
				(tracks allowed)
				(vias not_allowed)
				(pads allowed)
				(copperpour not_allowed)
				(footprints allowed)
			)
			(placement
				(enabled no)
				(sheetname "")
			)
			(fill
				(thermal_gap 0.5)
				(thermal_bridge_width 0.5)
				(island_removal_mode 0)
			)
			(polygon
				(pts
					(xy 180.127148 -73.60285) (xy 180.127148 -74.11085) (xy 179.746148 -74.11085) (xy 179.746148 -73.60285)
				)
			)
		)
	)
)
